# S9S_MB_2U (Grand Teton) — schematic netlist excerpt (pin names and nets, part order shuffled) for the footprints in the layout excerpt that follows; sources: Cadence DE-HDL packaged netlist, KiCad conversion of 03242023_DA0F0TMBIJ0_F0T_Motherboard_J_brd_V01_OCP.brd

R4798  Q_RES  10K 1% CHIP  pkg 0402LF  page 144 : A = P3V3_AUX ; B = PRSNT_CABLE_GPU_A3_N
R3465  Q_RES  10K 1% CHIP  pkg 0402LF  page 147 : A = P3V3_AUX ; B = GPU_HMC_PRSNT_N

(kicad_pcb
	(version 20260206)
	(generator "pcbnew")
	(generator_version "10.0")
	(general
		(thickness 1.6)
		(legacy_teardrops no)
	)
	(paper "A4")
	(title_block
		(title "03242023_DA0F0TMBIJ0_F0T_Motherboard_J_brd_V01_OCP.brd")
		(comment 1 "Grand Teton / footprints 4050-4051 of 6105")
	)
	(layers
		(0 "F.Cu" signal "TOP")
		(4 "In1.Cu" signal "GND")
		(6 "In2.Cu" signal "IN1")
		(8 "In3.Cu" signal "GND1")
		(10 "In4.Cu" signal "IN2")
		(12 "In5.Cu" signal "GND2")
		(14 "In6.Cu" signal "IN3")
		(16 "In7.Cu" signal "GND3")
		(18 "In8.Cu" signal "VCC")
		(20 "In9.Cu" signal "VCC1")
		(22 "In10.Cu" signal "GND4")
		(24 "In11.Cu" signal "IN4")
		(26 "In12.Cu" signal "GND5")
		(28 "In13.Cu" signal "IN5")
		(30 "In14.Cu" signal "GND6")
		(32 "In15.Cu" signal "IN6")
		(34 "In16.Cu" signal "GND7")
		(2 "B.Cu" signal "BOTTOM")
		(9 "F.Adhes" user "F.Adhesive")
		(11 "B.Adhes" user "B.Adhesive")
		(13 "F.Paste" user "Package Geometry/Pastemask Top")
		(15 "B.Paste" user "Package Geometry/Pastemask Bottom")
		(5 "F.SilkS" user "Ref Des/Silkscreen Top")
		(7 "B.SilkS" user "Ref Des/Silkscreen Bottom")
		(1 "F.Mask" user "Board Geometry/Soldermask Top")
		(3 "B.Mask" user "Board Geometry/Soldermask Bottom")
		(17 "Dwgs.User" user "User.Drawings")
		(19 "Cmts.User" user "User.Comments")
		(21 "Eco1.User" user "User.Eco1")
		(23 "Eco2.User" user "User.Eco2")
		(25 "Edge.Cuts" user "Board Geometry/Outline")
		(27 "Margin" user)
		(31 "F.CrtYd" user "Package Geometry/Place Bound Top")
		(29 "B.CrtYd" user "Package Geometry/Place Bound Bottom")
		(35 "F.Fab" user "Ref Des/Assembly Top")
		(33 "B.Fab" user "Ref Des/Assembly Bottom")
	)
	(footprint ""
		(layer "F.Cu")
		(at 365.2012 -412.623 180)
		(property "Reference" "R4798"
			(at 0 0 180)
			(layer "F.SilkS")
			(hide yes)
			(effects
				(font
					(size 1.27 1.27)
				)
			)
		)
		(property "Value" ""
			(at 0 0 180)
			(layer "F.Fab")
			(effects
				(font
					(size 1.27 1.27)
				)
			)
		)
		(duplicate_pad_numbers_are_jumpers no)
		(fp_line
			(start 0.7874 0.4064)
			(end -0.7874 0.4064)
			(stroke
				(width 0.1524)
				(type default)
			)
			(layer "F.SilkS")
		)
		(fp_line
			(start 0.7874 -0.4064)
			(end 0.7874 0.4064)
			(stroke
				(width 0.1524)
				(type default)
			)
			(layer "F.SilkS")
		)
		(fp_line
			(start -0.7874 0.4064)
			(end -0.7874 -0.4064)
			(stroke
				(width 0.1524)
				(type default)
			)
			(layer "F.SilkS")
		)
		(fp_line
			(start -0.7874 -0.4064)
			(end 0.7874 -0.4064)
			(stroke
				(width 0.1524)
				(type default)
			)
			(layer "F.SilkS")
		)
		(fp_line
			(start 0.67945 0.3048)
			(end 0.120396 0.3048)
			(stroke
				(width 0.1)
				(type default)
			)
			(layer "F.Fab")
		)
		(fp_line
			(start 0.67945 -0.3048)
			(end 0.67945 0.3048)
			(stroke
				(width 0.1)
				(type default)
			)
			(layer "F.Fab")
		)
		(fp_line
			(start 0.12065 -0.2794)
			(end 0.12065 -0.3048)
			(stroke
				(width 0.1)
				(type default)
			)
			(layer "F.Fab")
		)
		(fp_line
			(start 0.12065 -0.3048)
			(end 0.67945 -0.3048)
			(stroke
				(width 0.1)
				(type default)
			)
			(layer "F.Fab")
		)
		(fp_line
			(start 0.120396 0.3048)
			(end 0.120396 0.2794)
			(stroke
				(width 0.1)
				(type default)
			)
			(layer "F.Fab")
		)
		(fp_line
			(start 0.120396 0.2794)
			(end -0.12065 0.2794)
			(stroke
				(width 0.1)
				(type default)
			)
			(layer "F.Fab")
		)
		(fp_line
			(start -0.12065 0.3048)
			(end -0.67945 0.3048)
			(stroke
				(width 0.1)
				(type default)
			)
			(layer "F.Fab")
		)
		(fp_line
			(start -0.12065 0.2794)
			(end -0.12065 0.3048)
			(stroke
				(width 0.1)
				(type default)
			)
			(layer "F.Fab")
		)
		(fp_line
			(start -0.12065 -0.2794)
			(end 0.12065 -0.2794)
			(stroke
				(width 0.1)
				(type default)
			)
			(layer "F.Fab")
		)
		(fp_line
			(start -0.12065 -0.305054)
			(end -0.12065 -0.2794)
			(stroke
				(width 0.1)
				(type default)
			)
			(layer "F.Fab")
		)
		(fp_line
			(start -0.67945 0.3048)
			(end -0.67945 -0.305054)
			(stroke
				(width 0.1)
				(type default)
			)
			(layer "F.Fab")
		)
		(fp_line
			(start -0.67945 -0.305054)
			(end -0.12065 -0.305054)
			(stroke
				(width 0.1)
				(type default)
			)
			(layer "F.Fab")
		)
		(pad "1" smd circle
			(at -0.40005 0 180)
			(size 0 0)
			(layers "F.Cu" "F.Mask" "F.Paste")
			(net "P3V3_AUX")
		)
		(pad "2" smd circle
			(at 0.40005 0 180)
			(size 0 0)
			(layers "F.Cu" "F.Mask" "F.Paste")
			(net "PRSNT_CABLE_GPU_A3_N")
		)
	)
	(footprint ""
		(layer "F.Cu")
		(at 176.059338 -415.713418 180)
		(property "Reference" "R3465"
			(at 0 0 180)
			(layer "F.SilkS")
			(hide yes)
			(effects
				(font
					(size 1.27 1.27)
				)
			)
		)
		(property "Value" ""
			(at 0 0 180)
			(layer "F.Fab")
			(effects
				(font
					(size 1.27 1.27)
				)
			)
		)
		(duplicate_pad_numbers_are_jumpers no)
		(fp_line
			(start 0.7874 0.4064)
			(end -0.7874 0.4064)
			(stroke
				(width 0.1524)
				(type default)
			)
			(layer "F.SilkS")
		)
		(fp_line
			(start 0.7874 -0.4064)
			(end 0.7874 0.4064)
			(stroke
				(width 0.1524)
				(type default)
			)
			(layer "F.SilkS")
		)
		(fp_line
			(start -0.7874 0.4064)
			(end -0.7874 -0.4064)
			(stroke
				(width 0.1524)
				(type default)
			)
			(layer "F.SilkS")
		)
		(fp_line
			(start -0.7874 -0.4064)
			(end 0.7874 -0.4064)
			(stroke
				(width 0.1524)
				(type default)
			)
			(layer "F.SilkS")
		)
		(fp_line
			(start 0.67945 0.3048)
			(end 0.120396 0.3048)
			(stroke
				(width 0.1)
				(type default)
			)
			(layer "F.Fab")
		)
		(fp_line
			(start 0.67945 -0.3048)
			(end 0.67945 0.3048)
			(stroke
				(width 0.1)
				(type default)
			)
			(layer "F.Fab")
		)
		(fp_line
			(start 0.12065 -0.2794)
			(end 0.12065 -0.3048)
			(stroke
				(width 0.1)
				(type default)
			)
			(layer "F.Fab")
		)
		(fp_line
			(start 0.12065 -0.3048)
			(end 0.67945 -0.3048)
			(stroke
				(width 0.1)
				(type default)
			)
			(layer "F.Fab")
		)
		(fp_line
			(start 0.120396 0.3048)
			(end 0.120396 0.2794)
			(stroke
				(width 0.1)
				(type default)
			)
			(layer "F.Fab")
		)
		(fp_line
			(start 0.120396 0.2794)
			(end -0.12065 0.2794)
			(stroke
				(width 0.1)
				(type default)
			)
			(layer "F.Fab")
		)
		(fp_line
			(start -0.12065 0.3048)
			(end -0.67945 0.3048)
			(stroke
				(width 0.1)
				(type default)
			)
			(layer "F.Fab")
		)
		(fp_line
			(start -0.12065 0.2794)
			(end -0.12065 0.3048)
			(stroke
				(width 0.1)
				(type default)
			)
			(layer "F.Fab")
		)
		(fp_line
			(start -0.12065 -0.2794)
			(end 0.12065 -0.2794)
			(stroke
				(width 0.1)
				(type default)
			)
			(layer "F.Fab")
		)
		(fp_line
			(start -0.12065 -0.305054)
			(end -0.12065 -0.2794)
			(stroke
				(width 0.1)
				(type default)
			)
			(layer "F.Fab")
		)
		(fp_line
			(start -0.67945 0.3048)
			(end -0.67945 -0.305054)
			(stroke
				(width 0.1)
				(type default)
			)
			(layer "F.Fab")
		)
		(fp_line
			(start -0.67945 -0.305054)
			(end -0.12065 -0.305054)
			(stroke
				(width 0.1)
				(type default)
			)
			(layer "F.Fab")
		)
		(pad "1" smd circle
			(at -0.40005 0 180)
			(size 0 0)
			(layers "F.Cu" "F.Mask" "F.Paste")
			(net "P3V3_AUX")
		)
		(pad "2" smd circle
			(at 0.40005 0 180)
			(size 0 0)
			(layers "F.Cu" "F.Mask" "F.Paste")
			(net "GPU_HMC_PRSNT_N")
		)
	)
)
